# SCM (Grand Teton) — schematic netlist excerpt (pin names and nets, part order shuffled) for the footprints in the layout excerpt that follows; sources: Cadence DE-HDL packaged netlist, KiCad conversion of 12092022_DA0F0TMDCD0_F0T_Management_Board_D_brd_V3_OCP.brd

C112  Q_CAP  0.1UF 25V 10% X7R  pkg 0402  page 16 : A = P1V2_AUX ; B = GND
C101  Q_CAP  0.1UF 25V 10% X7R  pkg 0402  page 16 : A = P3V3_AUX ; B = GND

(kicad_pcb
	(version 20260206)
	(generator "pcbnew")
	(generator_version "10.0")
	(general
		(thickness 1.6)
		(legacy_teardrops no)
	)
	(paper "A4")
	(title_block
		(title "12092022_DA0F0TMDCD0_F0T_Management_Board_D_brd_V3_OCP.brd")
		(comment 1 "Grand Teton / footprints 1109-1110 of 1440")
	)
	(layers
		(0 "F.Cu" signal "TOP")
		(4 "In1.Cu" signal "GND")
		(6 "In2.Cu" signal "IN1")
		(8 "In3.Cu" signal "GND1")
		(10 "In4.Cu" signal "IN2")
		(12 "In5.Cu" signal "VCC")
		(14 "In6.Cu" signal "VCC1")
		(16 "In7.Cu" signal "IN3")
		(18 "In8.Cu" signal "GND2")
		(20 "In9.Cu" signal "IN4")
		(22 "In10.Cu" signal "GND3")
		(2 "B.Cu" signal "BOTTOM")
		(9 "F.Adhes" user "F.Adhesive")
		(11 "B.Adhes" user "B.Adhesive")
		(13 "F.Paste" user "Package Geometry/Pastemask Top")
		(15 "B.Paste" user "Package Geometry/Pastemask Bottom")
		(5 "F.SilkS" user "Ref Des/Silkscreen Top")
		(7 "B.SilkS" user "Ref Des/Silkscreen Bottom")
		(1 "F.Mask" user "Board Geometry/Soldermask Top")
		(3 "B.Mask" user "Board Geometry/Soldermask Bottom")
		(17 "Dwgs.User" user "User.Drawings")
		(19 "Cmts.User" user "User.Comments")
		(21 "Eco1.User" user "User.Eco1")
		(23 "Eco2.User" user "User.Eco2")
		(25 "Edge.Cuts" user "Board Geometry/Outline")
		(27 "Margin" user)
		(31 "F.CrtYd" user "Package Geometry/Place Bound Top")
		(29 "B.CrtYd" user "Package Geometry/Place Bound Bottom")
		(35 "F.Fab" user "Ref Des/Assembly Top")
		(33 "B.Fab" user "Ref Des/Assembly Bottom")
	)
	(footprint ""
		(layer "B.Cu")
		(at 51.30546 -51.69154 180)
		(property "Reference" "C112"
			(at 0 0 0)
			(layer "B.SilkS")
			(hide yes)
			(effects
				(font
					(size 1.27 1.27)
				)
				(justify mirror)
			)
		)
		(property "Value" ""
			(at 0 0 0)
			(layer "B.Fab")
			(effects
				(font
					(size 1.27 1.27)
				)
				(justify mirror)
			)
		)
		(duplicate_pad_numbers_are_jumpers no)
		(fp_line
			(start 0.7874 0.4064)
			(end 0.7874 -0.4064)
			(stroke
				(width 0.1524)
				(type default)
			)
			(layer "B.SilkS")
		)
		(fp_line
			(start 0.7874 -0.4064)
			(end -0.7874 -0.4064)
			(stroke
				(width 0.1524)
				(type default)
			)
			(layer "B.SilkS")
		)
		(fp_line
			(start -0.7874 0.4064)
			(end 0.7874 0.4064)
			(stroke
				(width 0.1524)
				(type default)
			)
			(layer "B.SilkS")
		)
		(fp_line
			(start -0.7874 -0.4064)
			(end -0.7874 0.4064)
			(stroke
				(width 0.1524)
				(type default)
			)
			(layer "B.SilkS")
		)
		(fp_line
			(start 0.67945 0.3048)
			(end 0.67945 -0.305054)
			(stroke
				(width 0.1)
				(type default)
			)
			(layer "B.Fab")
		)
		(fp_line
			(start 0.67945 -0.305054)
			(end 0.12065 -0.305054)
			(stroke
				(width 0.1)
				(type default)
			)
			(layer "B.Fab")
		)
		(fp_line
			(start 0.12065 0.3048)
			(end 0.67945 0.3048)
			(stroke
				(width 0.1)
				(type default)
			)
			(layer "B.Fab")
		)
		(fp_line
			(start 0.12065 0.2794)
			(end 0.12065 0.3048)
			(stroke
				(width 0.1)
				(type default)
			)
			(layer "B.Fab")
		)
		(fp_line
			(start 0.12065 -0.2794)
			(end -0.12065 -0.2794)
			(stroke
				(width 0.1)
				(type default)
			)
			(layer "B.Fab")
		)
		(fp_line
			(start 0.12065 -0.305054)
			(end 0.12065 -0.2794)
			(stroke
				(width 0.1)
				(type default)
			)
			(layer "B.Fab")
		)
		(fp_line
			(start -0.120396 0.3048)
			(end -0.120396 0.2794)
			(stroke
				(width 0.1)
				(type default)
			)
			(layer "B.Fab")
		)
		(fp_line
			(start -0.120396 0.2794)
			(end 0.12065 0.2794)
			(stroke
				(width 0.1)
				(type default)
			)
			(layer "B.Fab")
		)
		(fp_line
			(start -0.12065 -0.2794)
			(end -0.12065 -0.3048)
			(stroke
				(width 0.1)
				(type default)
			)
			(layer "B.Fab")
		)
		(fp_line
			(start -0.12065 -0.3048)
			(end -0.67945 -0.3048)
			(stroke
				(width 0.1)
				(type default)
			)
			(layer "B.Fab")
		)
		(fp_line
			(start -0.67945 0.3048)
			(end -0.120396 0.3048)
			(stroke
				(width 0.1)
				(type default)
			)
			(layer "B.Fab")
		)
		(fp_line
			(start -0.67945 -0.3048)
			(end -0.67945 0.3048)
			(stroke
				(width 0.1)
				(type default)
			)
			(layer "B.Fab")
		)
		(pad "1" smd circle
			(at 0.40005 0)
			(size 0 0)
			(layers "B.Cu" "B.Mask" "B.Paste")
			(net "P1V2_AUX")
		)
		(pad "2" smd circle
			(at -0.40005 0)
			(size 0 0)
			(layers "B.Cu" "B.Mask" "B.Paste")
			(net "GND")
		)
	)
	(footprint ""
		(layer "B.Cu")
		(at 51.558952 -43.765216)
		(property "Reference" "C101"
			(at 0 0 0)
			(layer "B.SilkS")
			(hide yes)
			(effects
				(font
					(size 1.27 1.27)
				)
				(justify mirror)
			)
		)
		(property "Value" ""
			(at 0 0 0)
			(layer "B.Fab")
			(effects
				(font
					(size 1.27 1.27)
				)
				(justify mirror)
			)
		)
		(duplicate_pad_numbers_are_jumpers no)
		(fp_line
			(start -0.7874 -0.4064)
			(end -0.7874 0.4064)
			(stroke
				(width 0.1524)
				(type default)
			)
			(layer "B.SilkS")
		)
		(fp_line
			(start -0.7874 0.4064)
			(end 0.7874 0.4064)
			(stroke
				(width 0.1524)
				(type default)
			)
			(layer "B.SilkS")
		)
		(fp_line
			(start 0.7874 -0.4064)
			(end -0.7874 -0.4064)
			(stroke
				(width 0.1524)
				(type default)
			)
			(layer "B.SilkS")
		)
		(fp_line
			(start 0.7874 0.4064)
			(end 0.7874 -0.4064)
			(stroke
				(width 0.1524)
				(type default)
			)
			(layer "B.SilkS")
		)
		(fp_line
			(start -0.67945 -0.3048)
			(end -0.67945 0.3048)
			(stroke
				(width 0.1)
				(type default)
			)
			(layer "B.Fab")
		)
		(fp_line
			(start -0.67945 0.3048)
			(end -0.120396 0.3048)
			(stroke
				(width 0.1)
				(type default)
			)
			(layer "B.Fab")
		)
		(fp_line
			(start -0.12065 -0.3048)
			(end -0.67945 -0.3048)
			(stroke
				(width 0.1)
				(type default)
			)
			(layer "B.Fab")
		)
		(fp_line
			(start -0.12065 -0.2794)
			(end -0.12065 -0.3048)
			(stroke
				(width 0.1)
				(type default)
			)
			(layer "B.Fab")
		)
		(fp_line
			(start -0.120396 0.2794)
			(end 0.12065 0.2794)
			(stroke
				(width 0.1)
				(type default)
			)
			(layer "B.Fab")
		)
		(fp_line
			(start -0.120396 0.3048)
			(end -0.120396 0.2794)
			(stroke
				(width 0.1)
				(type default)
			)
			(layer "B.Fab")
		)
		(fp_line
			(start 0.12065 -0.305054)
			(end 0.12065 -0.2794)
			(stroke
				(width 0.1)
				(type default)
			)
			(layer "B.Fab")
		)
		(fp_line
			(start 0.12065 -0.2794)
			(end -0.12065 -0.2794)
			(stroke
				(width 0.1)
				(type default)
			)
			(layer "B.Fab")
		)
		(fp_line
			(start 0.12065 0.2794)
			(end 0.12065 0.3048)
			(stroke
				(width 0.1)
				(type default)
			)
			(layer "B.Fab")
		)
		(fp_line
			(start 0.12065 0.3048)
			(end 0.67945 0.3048)
			(stroke
				(width 0.1)
				(type default)
			)
			(layer "B.Fab")
		)
		(fp_line
			(start 0.67945 -0.305054)
			(end 0.12065 -0.305054)
			(stroke
				(width 0.1)
				(type default)
			)
			(layer "B.Fab")
		)
		(fp_line
			(start 0.67945 0.3048)
			(end 0.67945 -0.305054)
			(stroke
				(width 0.1)
				(type default)
			)
			(layer "B.Fab")
		)
		(pad "1" smd circle
			(at 0.40005 0 180)
			(size 0 0)
			(layers "B.Cu" "B.Mask" "B.Paste")
			(net "P3V3_AUX")
		)
		(pad "2" smd circle
			(at -0.40005 0 180)
			(size 0 0)
			(layers "B.Cu" "B.Mask" "B.Paste")
			(net "GND")
		)
	)
)
